# BASEBOARD_FAB2 (Tioga Pass) — schematic netlist excerpt (pin names and nets, part order shuffled) for the footprints in the layout excerpt that follows; sources: Cadence DE-HDL packaged netlist, KiCad conversion of Wiwynn_Tioga_Pass_MB.brd

C8P26  CAP  47UF 4V 20% X6S  pkg 0805  page 76 : A = PVCCIN_CPU1 ; B = GND
R25W121  RES  20.0 1% CHIP  pkg 0402  page 145 : A = SMB_PEHPCPU0_STBY_LVC3_R_SDA ; B = SMB_PEHPCPU0_STBY_LVC3_R2_SDA
R7D3  RES  4.75K 1% CHIP  pkg 0402  page 133 : A = P3V3_STBY ; B = IRQ_LPC_SERIRQ_N

(kicad_pcb
	(version 20260206)
	(generator "pcbnew")
	(generator_version "10.0")
	(general
		(thickness 1.6)
		(legacy_teardrops no)
	)
	(paper "A4")
	(title_block
		(title "Wiwynn_Tioga_Pass_MB.brd")
		(comment 1 "Tioga Pass / footprints 2778-2780 of 4770")
	)
	(layers
		(0 "F.Cu" signal "TOP")
		(4 "In1.Cu" signal "L2GND")
		(6 "In2.Cu" signal "L3")
		(8 "In3.Cu" signal "L4GND")
		(10 "In4.Cu" signal "L5")
		(12 "In5.Cu" signal "L6GND")
		(14 "In6.Cu" signal "L7VCC")
		(16 "In7.Cu" signal "L8VCC")
		(18 "In8.Cu" signal "L9GND")
		(20 "In9.Cu" signal "L10")
		(22 "In10.Cu" signal "L11GND")
		(24 "In11.Cu" signal "L12")
		(26 "In12.Cu" signal "L13GND")
		(2 "B.Cu" signal "BOTTOM")
		(9 "F.Adhes" user "F.Adhesive")
		(11 "B.Adhes" user "B.Adhesive")
		(13 "F.Paste" user "Package Geometry/Pastemask Top")
		(15 "B.Paste" user "Package Geometry/Pastemask Bottom")
		(5 "F.SilkS" user "Ref Des/Silkscreen Top")
		(7 "B.SilkS" user "Ref Des/Silkscreen Bottom")
		(1 "F.Mask" user "Board Geometry/Soldermask Top")
		(3 "B.Mask" user "Board Geometry/Soldermask Bottom")
		(17 "Dwgs.User" user "User.Drawings")
		(19 "Cmts.User" user "User.Comments")
		(21 "Eco1.User" user "User.Eco1")
		(23 "Eco2.User" user "User.Eco2")
		(25 "Edge.Cuts" user "Board Geometry/Outline")
		(27 "Margin" user)
		(31 "F.CrtYd" user "Package Geometry/Place Bound Top")
		(29 "B.CrtYd" user "Package Geometry/Place Bound Bottom")
		(35 "F.Fab" user "Ref Des/Assembly Top")
		(33 "B.Fab" user "Ref Des/Assembly Bottom")
	)
	(footprint ""
		(layer "B.Cu")
		(at 405.3586 -34.313368 90)
		(property "Reference" "R25W121"
			(at 0.8382 -0.67818 90)
			(unlocked yes)
			(layer "B.SilkS")
			(effects
				(font
					(size 0.4064 0.254)
					(thickness 0.1524)
				)
				(justify left mirror)
			)
		)
		(property "Value" ""
			(at 0 0 90)
			(layer "B.Fab")
			(effects
				(font
					(size 1.27 1.27)
				)
				(justify mirror)
			)
		)
		(duplicate_pad_numbers_are_jumpers no)
		(fp_poly
			(pts
				(xy 0.2794 -0.1016) (xy -0.2794 -0.1016) (xy -0.2794 0.9906) (xy 0.2794 0.9906)
			)
			(stroke
				(width 0)
				(type default)
			)
			(fill no)
			(layer "B.CrtYd")
		)
		(fp_line
			(start 0.2794 -0.1016)
			(end 0.2794 0.9906)
			(stroke
				(width 0.1)
				(type default)
			)
			(layer "B.Fab")
		)
		(fp_line
			(start -0.2794 -0.1016)
			(end 0.2794 -0.1016)
			(stroke
				(width 0.1)
				(type default)
			)
			(layer "B.Fab")
		)
		(fp_line
			(start 0.2794 0.9906)
			(end -0.2794 0.9906)
			(stroke
				(width 0.1)
				(type default)
			)
			(layer "B.Fab")
		)
		(fp_line
			(start -0.2794 0.9906)
			(end -0.2794 -0.1016)
			(stroke
				(width 0.1)
				(type default)
			)
			(layer "B.Fab")
		)
		(pad "1" smd rect
			(at 0 0 270)
			(size 0.508 0.508)
			(layers "B.Cu" "B.Mask" "B.Paste")
			(net "SMB_PEHPCPU0_STBY_LVC3_R_SDA")
		)
		(pad "2" smd rect
			(at 0 0.889 270)
			(size 0.508 0.508)
			(layers "B.Cu" "B.Mask" "B.Paste")
			(net "SMB_PEHPCPU0_STBY_LVC3_R2_SDA")
		)
		(zone
			(layer "B.Cu")
			(hatch none 0.5)
			(connect_pads
				(clearance 0)
			)
			(min_thickness 0.25)
			(keepout
				(tracks allowed)
				(vias not_allowed)
				(pads allowed)
				(copperpour not_allowed)
				(footprints allowed)
			)
			(placement
				(enabled no)
				(sheetname "")
			)
			(fill
				(thermal_gap 0.5)
				(thermal_bridge_width 0.5)
				(island_removal_mode 0)
			)
			(polygon
				(pts
					(xy 405.6126 -34.567368) (xy 405.6126 -34.059368) (xy 405.9936 -34.059368) (xy 405.9936 -34.567368)
				)
			)
		)
		(zone
			(layer "B.Cu")
			(hatch none 0.5)
			(connect_pads
				(clearance 0)
			)
			(min_thickness 0.25)
			(keepout
				(tracks not_allowed)
				(vias allowed)
				(pads allowed)
				(copperpour not_allowed)
				(footprints allowed)
			)
			(placement
				(enabled no)
				(sheetname "")
			)
			(fill
				(thermal_gap 0.5)
				(thermal_bridge_width 0.5)
				(island_removal_mode 0)
			)
			(polygon
				(pts
					(xy 405.9936 -34.567368) (xy 405.9936 -34.059368) (xy 405.6126 -34.059368) (xy 405.6126 -34.567368)
				)
			)
		)
	)
	(footprint ""
		(layer "B.Cu")
		(at 99.034854 -73.51014)
		(property "Reference" "C8P26"
			(at 0 0 0)
			(layer "B.SilkS")
			(hide yes)
			(effects
				(font
					(size 1.27 1.27)
				)
				(justify mirror)
			)
		)
		(property "Value" ""
			(at 0 0 0)
			(layer "B.Fab")
			(effects
				(font
					(size 1.27 1.27)
				)
				(justify mirror)
			)
		)
		(duplicate_pad_numbers_are_jumpers no)
		(fp_poly
			(pts
				(xy 0.7239 -0.2159) (xy -0.7239 -0.2159) (xy -0.7239 1.9939) (xy 0.7239 1.9939)
			)
			(stroke
				(width 0)
				(type default)
			)
			(fill no)
			(layer "B.CrtYd")
		)
		(fp_line
			(start -0.7239 -0.2159)
			(end 0.7239 -0.2159)
			(stroke
				(width 0.1)
				(type default)
			)
			(layer "B.Fab")
		)
		(fp_line
			(start -0.7239 1.9939)
			(end -0.7239 -0.2159)
			(stroke
				(width 0.1)
				(type default)
			)
			(layer "B.Fab")
		)
		(fp_line
			(start 0.7239 -0.2159)
			(end 0.7239 1.9939)
			(stroke
				(width 0.1)
				(type default)
			)
			(layer "B.Fab")
		)
		(fp_line
			(start 0.7239 1.9939)
			(end -0.7239 1.9939)
			(stroke
				(width 0.1)
				(type default)
			)
			(layer "B.Fab")
		)
		(pad "1" smd rect
			(at 0 0 180)
			(size 1.27 1.016)
			(layers "B.Cu" "B.Mask" "B.Paste")
			(net "PVCCIN_CPU1")
		)
		(pad "2" smd rect
			(at 0 1.778 180)
			(size 1.27 1.016)
			(layers "B.Cu" "B.Mask" "B.Paste")
			(net "GND")
		)
		(zone
			(layer "B.Cu")
			(hatch none 0.5)
			(connect_pads
				(clearance 0)
			)
			(min_thickness 0.25)
			(keepout
				(tracks not_allowed)
				(vias allowed)
				(pads allowed)
				(copperpour not_allowed)
				(footprints allowed)
			)
			(placement
				(enabled no)
				(sheetname "")
			)
			(fill
				(thermal_gap 0.5)
				(thermal_bridge_width 0.5)
				(island_removal_mode 0)
			)
			(polygon
				(pts
					(xy 99.669854 -73.00214) (xy 98.399854 -73.00214) (xy 98.399854 -72.24014) (xy 99.669854 -72.24014)
				)
			)
		)
	)
	(footprint ""
		(layer "B.Cu")
		(at 379.984 -87.3125 180)
		(property "Reference" "R7D3"
			(at 0 0 0)
			(layer "B.SilkS")
			(hide yes)
			(effects
				(font
					(size 1.27 1.27)
				)
				(justify mirror)
			)
		)
		(property "Value" ""
			(at 0 0 0)
			(layer "B.Fab")
			(effects
				(font
					(size 1.27 1.27)
				)
				(justify mirror)
			)
		)
		(duplicate_pad_numbers_are_jumpers no)
		(fp_poly
			(pts
				(xy 0.2794 -0.1016) (xy -0.2794 -0.1016) (xy -0.2794 0.9906) (xy 0.2794 0.9906)
			)
			(stroke
				(width 0)
				(type default)
			)
			(fill no)
			(layer "B.CrtYd")
		)
		(fp_line
			(start 0.2794 0.9906)
			(end -0.2794 0.9906)
			(stroke
				(width 0.1)
				(type default)
			)
			(layer "B.Fab")
		)
		(fp_line
			(start 0.2794 -0.1016)
			(end 0.2794 0.9906)
			(stroke
				(width 0.1)
				(type default)
			)
			(layer "B.Fab")
		)
		(fp_line
			(start -0.2794 0.9906)
			(end -0.2794 -0.1016)
			(stroke
				(width 0.1)
				(type default)
			)
			(layer "B.Fab")
		)
		(fp_line
			(start -0.2794 -0.1016)
			(end 0.2794 -0.1016)
			(stroke
				(width 0.1)
				(type default)
			)
			(layer "B.Fab")
		)
		(pad "1" smd rect
			(at 0 0)
			(size 0.508 0.508)
			(layers "B.Cu" "B.Mask" "B.Paste")
			(net "P3V3_STBY")
		)
		(pad "2" smd rect
			(at 0 0.889)
			(size 0.508 0.508)
			(layers "B.Cu" "B.Mask" "B.Paste")
			(net "IRQ_LPC_SERIRQ_N")
		)
		(zone
			(layer "B.Cu")
			(hatch none 0.5)
			(connect_pads
				(clearance 0)
			)
			(min_thickness 0.25)
			(keepout
				(tracks not_allowed)
				(vias allowed)
				(pads allowed)
				(copperpour not_allowed)
				(footprints allowed)
			)
			(placement
				(enabled no)
				(sheetname "")
			)
			(fill
				(thermal_gap 0.5)
				(thermal_bridge_width 0.5)
				(island_removal_mode 0)
			)
			(polygon
				(pts
					(xy 379.73 -87.9475) (xy 380.238 -87.9475) (xy 380.238 -87.5665) (xy 379.73 -87.5665)
				)
			)
		)
		(zone
			(layer "B.Cu")
			(hatch none 0.5)
			(connect_pads
				(clearance 0)
			)
			(min_thickness 0.25)
			(keepout
				(tracks allowed)
				(vias not_allowed)
				(pads allowed)
				(copperpour not_allowed)
				(footprints allowed)
			)
			(placement
				(enabled no)
				(sheetname "")
			)
			(fill
				(thermal_gap 0.5)
				(thermal_bridge_width 0.5)
				(island_removal_mode 0)
			)
			(polygon
				(pts
					(xy 379.73 -87.5665) (xy 380.238 -87.5665) (xy 380.238 -87.9475) (xy 379.73 -87.9475)
				)
			)
		)
	)
)
